# SO-DIMM DDR5 Tester — KiCad project settings (.kicad_pro: net classes, design rules, text variables)
{
  "board": {
    "3dviewports": [],
    "design_settings": {
      "defaults": {
        "apply_defaults_to_fp_fields": false,
        "apply_defaults_to_fp_shapes": false,
        "apply_defaults_to_fp_text": false,
        "board_outline_line_width": 0.1,
        "copper_line_width": 0.2,
        "copper_text_italic": false,
        "copper_text_size_h": 1.5,
        "copper_text_size_v": 1.5,
        "copper_text_thickness": 0.3,
        "copper_text_upright": false,
        "courtyard_line_width": 0.05,
        "dimension_precision": 4,
        "dimension_units": 3,
        "dimensions": {
          "arrow_length": 1270000,
          "extension_offset": 500000,
          "keep_text_aligned": true,
          "suppress_zeroes": false,
          "text_position": 0,
          "units_format": 1
        },
        "fab_line_width": 0.1,
        "fab_text_italic": false,
        "fab_text_size_h": 1.0,
        "fab_text_size_v": 1.0,
        "fab_text_thickness": 0.15,
        "fab_text_upright": false,
        "other_line_width": 0.1,
        "other_text_italic": false,
        "other_text_size_h": 1.0,
        "other_text_size_v": 1.0,
        "other_text_thickness": 0.15,
        "other_text_upright": false,
        "pads": {
          "drill": 0.0,
          "height": 1.0,
          "width": 1.0
        },
        "silk_line_width": 0.15,
        "silk_text_italic": false,
        "silk_text_size_h": 0.7,
        "silk_text_size_v": 0.7,
        "silk_text_thickness": 0.15,
        "silk_text_upright": false,
        "zones": {
          "45_degree_only": false,
          "min_clearance": 0.12
        }
      },
      "diff_pair_dimensions": [
        {
          "gap": 0.0,
          "via_gap": 0.0,
          "width": 0.0
        }
      ],
      "drc_exclusions": [],
      "meta": {
        "filename": "board_design_settings.json",
        "version": 2
      },
      "rule_severities": {
        "annular_width": "error",
        "clearance": "error",
        "connection_width": "warning",
        "copper_edge_clearance": "error",
        "copper_sliver": "warning",
        "courtyards_overlap": "ignore",
        "creepage": "error",
        "diff_pair_gap_out_of_range": "error",
        "diff_pair_uncoupled_length_too_long": "error",
        "drill_out_of_range": "error",
        "duplicate_footprints": "warning",
        "extra_footprint": "warning",
        "footprint": "error",
        "footprint_filters_mismatch": "ignore",
        "footprint_symbol_mismatch": "warning",
        "footprint_type_mismatch": "error",
        "hole_clearance": "error",
        "hole_near_hole": "error",
        "hole_to_hole": "error",
        "holes_co_located": "warning",
        "invalid_outline": "error",
        "isolated_copper": "warning",
        "item_on_disabled_layer": "error",
        "items_not_allowed": "error",
        "length_out_of_range": "error",
        "lib_footprint_issues": "ignore",
        "lib_footprint_mismatch": "ignore",
        "malformed_courtyard": "ignore",
        "microvia_drill_out_of_range": "error",
        "mirrored_text_on_front_layer": "warning",
        "missing_courtyard": "ignore",
        "missing_footprint": "warning",
        "net_conflict": "warning",
        "nonmirrored_text_on_back_layer": "warning",
        "npth_inside_courtyard": "ignore",
        "padstack": "error",
        "pth_inside_courtyard": "ignore",
        "shorting_items": "error",
        "silk_edge_clearance": "ignore",
        "silk_over_copper": "ignore",
        "silk_overlap": "ignore",
        "skew_out_of_range": "error",
        "solder_mask_bridge": "ignore",
        "starved_thermal": "ignore",
        "text_height": "warning",
        "text_on_edge_cuts": "error",
        "text_thickness": "warning",
        "through_hole_pad_without_hole": "error",
        "too_many_vias": "error",
        "track_angle": "error",
        "track_dangling": "error",
        "track_segment_length": "error",
        "track_width": "error",
        "tracks_crossing": "error",
        "unconnected_items": "error",
        "unresolved_variable": "error",
        "via_dangling": "ignore",
        "zones_intersect": "error"
      },
      "rule_severitieslegacy_courtyards_overlap": true,
      "rule_severitieslegacy_no_courtyard_defined": false,
      "rules": {
        "allow_blind_buried_vias": false,
        "allow_microvias": false,
        "max_error": 0.005,
        "min_clearance": 0.1,
        "min_connection": 0.0,
        "min_copper_edge_clearance": 0.2,
        "min_groove_width": 0.0,
        "min_hole_clearance": 0.2,
        "min_hole_to_hole": 0.25,
        "min_microvia_diameter": 0.2,
        "min_microvia_drill": 0.1,
        "min_resolved_spokes": 2,
        "min_silk_clearance": 0.0,
        "min_text_height": 0.7,
        "min_text_thickness": 0.08,
        "min_through_hole_diameter": 0.1,
        "min_track_width": 0.1,
        "min_via_annular_width": 0.125,
        "min_via_diameter": 0.45,
        "solder_mask_to_copper_clearance": 0.0,
        "use_height_for_length_calcs": true
      },
      "teardrop_options": [
        {
          "td_onpthpad": true,
          "td_onroundshapesonly": false,
          "td_onsmdpad": true,
          "td_ontrackend": false,
          "td_onvia": true
        }
      ],
      "teardrop_parameters": [
        {
          "td_allow_use_two_tracks": true,
          "td_curve_segcount": 1,
          "td_height_ratio": 1.0,
          "td_length_ratio": 0.5,
          "td_maxheight": 2.0,
          "td_maxlen": 1.0,
          "td_on_pad_in_zone": false,
          "td_target_name": "td_round_shape",
          "td_width_to_size_filter_ratio": 0.9
        },
        {
          "td_allow_use_two_tracks": true,
          "td_curve_segcount": 1,
          "td_height_ratio": 1.0,
          "td_length_ratio": 0.5,
          "td_maxheight": 2.0,
          "td_maxlen": 1.0,
          "td_on_pad_in_zone": false,
          "td_target_name": "td_rect_shape",
          "td_width_to_size_filter_ratio": 0.9
        },
        {
          "td_allow_use_two_tracks": true,
          "td_curve_segcount": 1,
          "td_height_ratio": 1.0,
          "td_length_ratio": 0.5,
          "td_maxheight": 2.0,
          "td_maxlen": 1.0,
          "td_on_pad_in_zone": false,
          "td_target_name": "td_track_end",
          "td_width_to_size_filter_ratio": 0.9
        }
      ],
      "track_widths": [
        0.0,
        0.1,
        0.107,
        0.114,
        0.15,
        0.177,
        0.182,
        0.198,
        0.201,
        0.256,
        0.4,
        2.0
      ],
      "tuning_pattern_settings": {
        "diff_pair_defaults": {
          "corner_radius_percentage": 80,
          "corner_style": 1,
          "max_amplitude": 1.0,
          "min_amplitude": 0.2,
          "single_sided": false,
          "spacing": 1.0
        },
        "diff_pair_skew_defaults": {
          "corner_radius_percentage": 80,
          "corner_style": 1,
          "max_amplitude": 1.0,
          "min_amplitude": 0.2,
          "single_sided": false,
          "spacing": 0.6
        },
        "single_track_defaults": {
          "corner_radius_percentage": 80,
          "corner_style": 1,
          "max_amplitude": 1.0,
          "min_amplitude": 0.2,
          "single_sided": false,
          "spacing": 0.6
        }
      },
      "via_dimensions": [
        {
          "diameter": 0.0,
          "drill": 0.0
        },
        {
          "diameter": 0.45,
          "drill": 0.1
        }
      ],
      "zones_allow_external_fillets": false,
      "zones_use_no_outline": true
    },
    "ipc2581": {
      "dist": "",
      "distpn": "",
      "internal_id": "",
      "mfg": "",
      "mpn": ""
    },
    "layer_pairs": [],
    "layer_presets": [],
    "viewports": []
  },
  "boards": [],
  "cvpcb": {
    "equivalence_files": []
  },
  "erc": {
    "erc_exclusions": [],
    "meta": {
      "version": 0
    },
    "pin_map": [
      [
        0,
        0,
        0,
        0,
        0,
        0,
        1,
        0,
        0,
        0,
        0,
        2
      ],
      [
        0,
        2,
        0,
        1,
        0,
        0,
        1,
        0,
        2,
        2,
        2,
        2
      ],
      [
        0,
        0,
        0,
        0,
        0,
        0,
        1,
        0,
        1,
        0,
        1,
        2
      ],
      [
        0,
        1,
        0,
        0,
        0,
        0,
        1,
        1,
        2,
        1,
        1,
        2
      ],
      [
        0,
        0,
        0,
        0,
        0,
        0,
        1,
        0,
        0,
        0,
        0,
        2
      ],
      [
        0,
        0,
        0,
        0,
        0,
        0,
        0,
        0,
        0,
        0,
        0,
        2
      ],
      [
        1,
        1,
        1,
        1,
        1,
        0,
        1,
        1,
        1,
        1,
        1,
        2
      ],
      [
        0,
        0,
        0,
        1,
        0,
        0,
        1,
        0,
        0,
        0,
        0,
        2
      ],
      [
        0,
        2,
        1,
        2,
        0,
        0,
        1,
        0,
        2,
        2,
        2,
        2
      ],
      [
        0,
        2,
        0,
        1,
        0,
        0,
        1,
        0,
        2,
        0,
        0,
        2
      ],
      [
        0,
        2,
        1,
        1,
        0,
        0,
        1,
        0,
        2,
        0,
        0,
        2
      ],
      [
        2,
        2,
        2,
        2,
        2,
        2,
        2,
        2,
        2,
        2,
        2,
        2
      ]
    ],
    "rule_severities": {
      "bus_definition_conflict": "error",
      "bus_entry_needed": "error",
      "bus_to_bus_conflict": "error",
      "bus_to_net_conflict": "error",
      "conflicting_netclasses": "error",
      "different_unit_footprint": "error",
      "different_unit_net": "error",
      "duplicate_reference": "error",
      "duplicate_sheet_names": "error",
      "endpoint_off_grid": "warning",
      "extra_units": "error",
      "footprint_filter": "ignore",
      "footprint_link_issues": "warning",
      "four_way_junction": "ignore",
      "global_label_dangling": "ignore",
      "hier_label_mismatch": "error",
      "label_dangling": "error",
      "label_multiple_wires": "warning",
      "lib_symbol_issues": "warning",
      "lib_symbol_mismatch": "warning",
      "missing_bidi_pin": "warning",
      "missing_input_pin": "warning",
      "missing_power_pin": "error",
      "missing_unit": "warning",
      "multiple_net_names": "warning",
      "net_not_bus_member": "warning",
      "no_connect_connected": "ignore",
      "no_connect_dangling": "warning",
      "pin_not_connected": "error",
      "pin_not_driven": "error",
      "pin_to_pin": "ignore",
      "power_pin_not_driven": "error",
      "same_local_global_label": "warning",
      "similar_label_and_power": "warning",
      "similar_labels": "warning",
      "similar_power": "warning",
      "simulation_model_issue": "ignore",
      "single_global_label": "ignore",
      "unannotated": "error",
      "unconnected_wire_endpoint": "warning",
      "undefined_netclass": "error",
      "unit_value_mismatch": "error",
      "unresolved_variable": "error",
      "wire_dangling": "error"
    }
  },
  "libraries": {
    "pinned_footprint_libs": [],
    "pinned_symbol_libs": []
  },
  "meta": {
    "filename": "sodimm-ddr5-tester.kicad_pro",
    "version": 3
  },
  "net_settings": {
    "classes": [
      {
        "bus_width": 12,
        "clearance": 0.1,
        "diff_pair_gap": 0.1,
        "diff_pair_via_gap": 0.25,
        "diff_pair_width": 0.1,
        "line_style": 0,
        "microvia_diameter": 0.3,
        "microvia_drill": 0.1,
        "name": "Default",
        "pcb_color": "rgba(0, 0, 0, 0.000)",
        "priority": 2147483647,
        "schematic_color": "rgba(0, 0, 0, 0.000)",
        "track_width": 0.1,
        "via_diameter": 0.45,
        "via_drill": 0.1,
        "wire_width": 6
      },
      {
        "bus_width": 12,
        "clearance": 0.1,
        "diff_pair_gap": 0.1,
        "diff_pair_via_gap": 0.25,
        "diff_pair_width": 0.1,
        "line_style": 0,
        "microvia_diameter": 0.3,
        "microvia_drill": 0.1,
        "name": "100Ohm-diff",
        "pcb_color": "rgb(255, 153, 0)",
        "priority": 0,
        "schematic_color": "rgba(0, 0, 0, 0.000)",
        "track_width": 0.1,
        "via_diameter": 0.45,
        "via_drill": 0.1,
        "wire_width": 6
      },
      {
        "bus_width": 12,
        "clearance": 0.2,
        "diff_pair_gap": 0.1,
        "diff_pair_via_gap": 0.25,
        "diff_pair_width": 0.1,
        "line_style": 0,
        "microvia_diameter": 0.3,
        "microvia_drill": 0.1,
        "name": "12V",
        "pcb_color": "rgb(255, 255, 255)",
        "priority": 1,
        "schematic_color": "rgba(0, 0, 0, 0.000)",
        "track_width": 0.1,
        "via_diameter": 0.45,
        "via_drill": 0.1,
        "wire_width": 6
      },
      {
        "bus_width": 12,
        "clearance": 0.1,
        "diff_pair_gap": 0.1,
        "diff_pair_via_gap": 0.25,
        "diff_pair_width": 0.1,
        "line_style": 0,
        "microvia_diameter": 0.3,
        "microvia_drill": 0.1,
        "name": "40Ohm-se_DQ",
        "pcb_color": "rgb(255, 0, 214)",
        "priority": 2,
        "schematic_color": "rgba(0, 0, 0, 0.000)",
        "track_width": 0.1,
        "via_diameter": 0.45,
        "via_drill": 0.1,
        "wire_width": 6
      },
      {
        "bus_width": 12,
        "clearance": 0.1,
        "diff_pair_gap": 0.1,
        "diff_pair_via_gap": 0.25,
        "diff_pair_width": 0.1,
        "line_style": 0,
        "microvia_diameter": 0.3,
        "microvia_drill": 0.1,
        "name": "50Ohm-se",
        "pcb_color": "rgb(255, 255, 0)",
        "priority": 3,
        "schematic_color": "rgba(0, 0, 0, 0.000)",
        "track_width": 0.1,
        "via_diameter": 0.45,
        "via_drill": 0.1,
        "wire_width": 6
      },
      {
        "bus_width": 12,
        "clearance": 0.1,
        "diff_pair_gap": 0.1,
        "diff_pair_via_gap": 0.25,
        "diff_pair_width": 0.1,
        "line_style": 0,
        "microvia_diameter": 0.3,
        "microvia_drill": 0.1,
        "name": "80Ohm-diff_DQS",
        "pcb_color": "rgb(0, 255, 0)",
        "priority": 4,
        "schematic_color": "rgba(0, 0, 0, 0.000)",
        "track_width": 0.1,
        "via_diameter": 0.45,
        "via_drill": 0.1,
        "wire_width": 6
      },
      {
        "bus_width": 12,
        "clearance": 0.1,
        "diff_pair_gap": 0.1,
        "diff_pair_via_gap": 0.25,
        "diff_pair_width": 0.1,
        "line_style": 0,
        "microvia_diameter": 0.3,
        "microvia_drill": 0.1,
        "name": "85Ohm-diff_PCIe",
        "pcb_color": "rgb(0, 255, 255)",
        "priority": 5,
        "schematic_color": "rgba(0, 0, 0, 0.000)",
        "track_width": 0.1,
        "via_diameter": 0.45,
        "via_drill": 0.1,
        "wire_width": 6
      },
      {
        "bus_width": 12,
        "clearance": 0.1,
        "diff_pair_gap": 0.1,
        "diff_pair_via_gap": 0.25,
        "diff_pair_width": 0.1,
        "line_style": 0,
        "microvia_diameter": 0.3,
        "microvia_drill": 0.1,
        "name": "90Ohm-diff",
        "pcb_color": "rgb(0, 255, 163)",
        "priority": 6,
        "schematic_color": "rgba(0, 0, 0, 0.000)",
        "track_width": 0.1,
        "via_diameter": 0.45,
        "via_drill": 0.1,
        "wire_width": 6
      },
      {
        "bus_width": 12,
        "clearance": 0.1,
        "diff_pair_gap": 0.25,
        "diff_pair_via_gap": 0.25,
        "diff_pair_width": 0.2,
        "line_style": 0,
        "microvia_diameter": 0.3,
        "microvia_drill": 0.1,
        "name": "Supply",
        "pcb_color": "rgb(255, 0, 0)",
        "priority": 7,
        "schematic_color": "rgba(0, 0, 0, 0.000)",
        "track_width": 0.1,
        "via_diameter": 0.45,
        "via_drill": 0.1,
        "wire_width": 6
      }
    ],
    "meta": {
      "version": 4
    },
    "net_colors": {
      "GND": "rgb(0, 0, 255)"
    },
    "netclass_assignments": null,
    "netclass_patterns": [
      {
        "netclass": "100Ohm-diff",
        "pattern": "/DDR5 SODIMM/A.CK0_N"
      },
      {
        "netclass": "100Ohm-diff",
        "pattern": "/DDR5 SODIMM/A.CK0_P"
      },
      {
        "netclass": "100Ohm-diff",
        "pattern": "/DDR5 SODIMM/A.CK1_N"
      },
      {
        "netclass": "100Ohm-diff",
        "pattern": "/DDR5 SODIMM/A.CK1_P"
      },
      {
        "netclass": "100Ohm-diff",
        "pattern": "/DDR5 SODIMM/B.CK0_N"
      },
      {
        "netclass": "100Ohm-diff",
        "pattern": "/DDR5 SODIMM/B.CK0_P"
      },
      {
        "netclass": "100Ohm-diff",
        "pattern": "/DDR5 SODIMM/B.CK1_N"
      },
      {
        "netclass": "100Ohm-diff",
        "pattern": "/DDR5 SODIMM/B.CK1_P"
      },
      {
        "netclass": "100Ohm-diff",
        "pattern": "/Ethernet/ETH1_N"
      },
      {
        "netclass": "100Ohm-diff",
        "pattern": "/Ethernet/ETH1_P"
      },
      {
        "netclass": "100Ohm-diff",
        "pattern": "/Ethernet/ETH2_N"
      },
      {
        "netclass": "100Ohm-diff",
        "pattern": "/Ethernet/ETH2_P"
      },
      {
        "netclass": "100Ohm-diff",
        "pattern": "/Ethernet/ETH3_N"
      },
      {
        "netclass": "100Ohm-diff",
        "pattern": "/Ethernet/ETH3_P"
      },
      {
        "netclass": "100Ohm-diff",
        "pattern": "/Ethernet/ETH4_N"
      },
      {
        "netclass": "100Ohm-diff",
        "pattern": "/Ethernet/ETH4_P"
      },
      {
        "netclass": "100Ohm-diff",
        "pattern": "/FPGA bank 12/HyperRAM.CK_N"
      },
      {
        "netclass": "100Ohm-diff",
        "pattern": "/FPGA bank 12/HyperRAM.CK_P"
      },
      {
        "netclass": "100Ohm-diff",
        "pattern": "/FPGA bank 16/HDMI.CLK_N"
      },
      {
        "netclass": "100Ohm-diff",
        "pattern": "/FPGA bank 16/HDMI.CLK_P"
      },
      {
        "netclass": "100Ohm-diff",
        "pattern": "/FPGA bank 16/HDMI.D0_N"
      },
      {
        "netclass": "100Ohm-diff",
        "pattern": "/FPGA bank 16/HDMI.D0_P"
      },
      {
        "netclass": "100Ohm-diff",
        "pattern": "/FPGA bank 16/HDMI.D1_N"
      },
      {
        "netclass": "100Ohm-diff",
        "pattern": "/FPGA bank 16/HDMI.D1_P"
      },
      {
        "netclass": "100Ohm-diff",
        "pattern": "/FPGA bank 16/HDMI.D2_N"
      },
      {
        "netclass": "100Ohm-diff",
        "pattern": "/FPGA bank 16/HDMI.D2_P"
      },
      {
        "netclass": "100Ohm-diff",
        "pattern": "/HDMI + SD Card/HDMI_CONN_CLK_N"
      },
      {
        "netclass": "100Ohm-diff",
        "pattern": "/HDMI + SD Card/HDMI_CONN_CLK_P"
      },
      {
        "netclass": "100Ohm-diff",
        "pattern": "/HDMI + SD Card/HDMI_CONN_D0_N"
      },
      {
        "netclass": "100Ohm-diff",
        "pattern": "/HDMI + SD Card/HDMI_CONN_D0_P"
      },
      {
        "netclass": "100Ohm-diff",
        "pattern": "/HDMI + SD Card/HDMI_CONN_D1_N"
      },
      {
        "netclass": "100Ohm-diff",
        "pattern": "/HDMI + SD Card/HDMI_CONN_D1_P"
      },
      {
        "netclass": "100Ohm-diff",
        "pattern": "/HDMI + SD Card/HDMI_CONN_D2_N"
      },
      {
        "netclass": "100Ohm-diff",
        "pattern": "/HDMI + SD Card/HDMI_CONN_D2_P"
      },
      {
        "netclass": "12V",
        "pattern": "/Supply/12V_PCIE_fused"
      },
      {
        "netclass": "12V",
        "pattern": "/Supply/12V_aux"
      },
      {
        "netclass": "12V",
        "pattern": "/Supply/12V_aux_fused"
      },
      {
        "netclass": "12V",
        "pattern": "VDC"
      },
      {
        "netclass": "40Ohm-se_DQ",
        "pattern": "/DDR5 SODIMM/A.DQ0"
      },
      {
        "netclass": "40Ohm-se_DQ",
        "pattern": "/DDR5 SODIMM/A.DQ1"
      },
      {
        "netclass": "40Ohm-se_DQ",
        "pattern": "/DDR5 SODIMM/A.DQ10"
      },
      {
        "netclass": "40Ohm-se_DQ",
        "pattern": "/DDR5 SODIMM/A.DQ11"
      },
      {
        "netclass": "40Ohm-se_DQ",
        "pattern": "/DDR5 SODIMM/A.DQ12"
      },
      {
        "netclass": "40Ohm-se_DQ",
        "pattern": "/DDR5 SODIMM/A.DQ13"
      },
      {
        "netclass": "40Ohm-se_DQ",
        "pattern": "/DDR5 SODIMM/A.DQ14"
      },
      {
        "netclass": "40Ohm-se_DQ",
        "pattern": "/DDR5 SODIMM/A.DQ15"
      },
      {
        "netclass": "40Ohm-se_DQ",
        "pattern": "/DDR5 SODIMM/A.DQ16"
      },
      {
        "netclass": "40Ohm-se_DQ",
        "pattern": "/DDR5 SODIMM/A.DQ17"
      },
      {
        "netclass": "40Ohm-se_DQ",
        "pattern": "/DDR5 SODIMM/A.DQ18"
      },
      {
        "netclass": "40Ohm-se_DQ",
        "pattern": "/DDR5 SODIMM/A.DQ19"
      },
      {
        "netclass": "40Ohm-se_DQ",
        "pattern": "/DDR5 SODIMM/A.DQ2"
      },
      {
        "netclass": "40Ohm-se_DQ",
        "pattern": "/DDR5 SODIMM/A.DQ20"
      },
      {
        "netclass": "40Ohm-se_DQ",
        "pattern": "/DDR5 SODIMM/A.DQ21"
      },
      {
        "netclass": "40Ohm-se_DQ",
        "pattern": "/DDR5 SODIMM/A.DQ22"
      },
      {
        "netclass": "40Ohm-se_DQ",
        "pattern": "/DDR5 SODIMM/A.DQ23"
      },
      {
        "netclass": "40Ohm-se_DQ",
        "pattern": "/DDR5 SODIMM/A.DQ24"
      },
      {
        "netclass": "40Ohm-se_DQ",
        "pattern": "/DDR5 SODIMM/A.DQ25"
      },
      {
        "netclass": "40Ohm-se_DQ",
        "pattern": "/DDR5 SODIMM/A.DQ26"
      },
      {
        "netclass": "40Ohm-se_DQ",
        "pattern": "/DDR5 SODIMM/A.DQ27"
      },
      {
        "netclass": "40Ohm-se_DQ",
        "pattern": "/DDR5 SODIMM/A.DQ28"
      },
      {
        "netclass": "40Ohm-se_DQ",
        "pattern": "/DDR5 SODIMM/A.DQ29"
      },
      {
        "netclass": "40Ohm-se_DQ",
        "pattern": "/DDR5 SODIMM/A.DQ3"
      },
      {
        "netclass": "40Ohm-se_DQ",
        "pattern": "/DDR5 SODIMM/A.DQ30"
      },
      {
        "netclass": "40Ohm-se_DQ",
        "pattern": "/DDR5 SODIMM/A.DQ31"
      },
      {
        "netclass": "40Ohm-se_DQ",
        "pattern": "/DDR5 SODIMM/A.DQ4"
      },
      {
        "netclass": "40Ohm-se_DQ",
        "pattern": "/DDR5 SODIMM/A.DQ5"
      },
      {
        "netclass": "40Ohm-se_DQ",
        "pattern": "/DDR5 SODIMM/A.DQ6"
      },
      {
        "netclass": "40Ohm-se_DQ",
        "pattern": "/DDR5 SODIMM/A.DQ7"
      },
      {
        "netclass": "40Ohm-se_DQ",
        "pattern": "/DDR5 SODIMM/A.DQ8"
      },
      {
        "netclass": "40Ohm-se_DQ",
        "pattern": "/DDR5 SODIMM/A.DQ9"
      },
      {
        "netclass": "40Ohm-se_DQ",
        "pattern": "/DDR5 SODIMM/A.~{DM0}"
      },
      {
        "netclass": "40Ohm-se_DQ",
        "pattern": "/DDR5 SODIMM/A.~{DM1}"
      },
      {
        "netclass": "40Ohm-se_DQ",
        "pattern": "/DDR5 SODIMM/A.~{DM2}"
      },
      {
        "netclass": "40Ohm-se_DQ",
        "pattern": "/DDR5 SODIMM/A.~{DM3}"
      },
      {
        "netclass": "40Ohm-se_DQ",
        "pattern": "/DDR5 SODIMM/B.DQ0"
      },
      {
        "netclass": "40Ohm-se_DQ",
        "pattern": "/DDR5 SODIMM/B.DQ1"
      },
      {
        "netclass": "40Ohm-se_DQ",
        "pattern": "/DDR5 SODIMM/B.DQ10"
      },
      {
        "netclass": "40Ohm-se_DQ",
        "pattern": "/DDR5 SODIMM/B.DQ11"
      },
      {
        "netclass": "40Ohm-se_DQ",
        "pattern": "/DDR5 SODIMM/B.DQ12"
      },
      {
        "netclass": "40Ohm-se_DQ",
        "pattern": "/DDR5 SODIMM/B.DQ13"
      },
      {
        "netclass": "40Ohm-se_DQ",
        "pattern": "/DDR5 SODIMM/B.DQ14"
      },
      {
        "netclass": "40Ohm-se_DQ",
        "pattern": "/DDR5 SODIMM/B.DQ15"
      },
      {
        "netclass": "40Ohm-se_DQ",
        "pattern": "/DDR5 SODIMM/B.DQ16"
      },
      {
        "netclass": "40Ohm-se_DQ",
        "pattern": "/DDR5 SODIMM/B.DQ17"
      },
      {
        "netclass": "40Ohm-se_DQ",
        "pattern": "/DDR5 SODIMM/B.DQ18"
      },
      {
        "netclass": "40Ohm-se_DQ",
        "pattern": "/DDR5 SODIMM/B.DQ19"
      },
      {
        "netclass": "40Ohm-se_DQ",
        "pattern": "/DDR5 SODIMM/B.DQ2"
      },
      {
        "netclass": "40Ohm-se_DQ",
        "pattern": "/DDR5 SODIMM/B.DQ20"
      },
      {
        "netclass": "40Ohm-se_DQ",
        "pattern": "/DDR5 SODIMM/B.DQ21"
      },
      {
        "netclass": "40Ohm-se_DQ",
        "pattern": "/DDR5 SODIMM/B.DQ22"
      },
      {
        "netclass": "40Ohm-se_DQ",
        "pattern": "/DDR5 SODIMM/B.DQ23"
      },
      {
        "netclass": "40Ohm-se_DQ",
        "pattern": "/DDR5 SODIMM/B.DQ24"
      },
      {
        "netclass": "40Ohm-se_DQ",
        "pattern": "/DDR5 SODIMM/B.DQ25"
      },
      {
        "netclass": "40Ohm-se_DQ",
        "pattern": "/DDR5 SODIMM/B.DQ26"
      },
      {
        "netclass": "40Ohm-se_DQ",
        "pattern": "/DDR5 SODIMM/B.DQ27"
      },
      {
        "netclass": "40Ohm-se_DQ",
        "pattern": "/DDR5 SODIMM/B.DQ28"
      },
      {
        "netclass": "40Ohm-se_DQ",
        "pattern": "/DDR5 SODIMM/B.DQ29"
      },
      {
        "netclass": "40Ohm-se_DQ",
        "pattern": "/DDR5 SODIMM/B.DQ3"
      },
      {
        "netclass": "40Ohm-se_DQ",
        "pattern": "/DDR5 SODIMM/B.DQ30"
      },
      {
        "netclass": "40Ohm-se_DQ",
        "pattern": "/DDR5 SODIMM/B.DQ31"
      },
      {
        "netclass": "40Ohm-se_DQ",
        "pattern": "/DDR5 SODIMM/B.DQ4"
      },
      {
        "netclass": "40Ohm-se_DQ",
        "pattern": "/DDR5 SODIMM/B.DQ5"
      },
      {
        "netclass": "40Ohm-se_DQ",
        "pattern": "/DDR5 SODIMM/B.DQ6"
      },
      {
        "netclass": "40Ohm-se_DQ",
        "pattern": "/DDR5 SODIMM/B.DQ7"
      },
      {
        "netclass": "40Ohm-se_DQ",
        "pattern": "/DDR5 SODIMM/B.DQ8"
      },
      {
        "netclass": "40Ohm-se_DQ",
        "pattern": "/DDR5 SODIMM/B.DQ9"
      },
      {
        "netclass": "40Ohm-se_DQ",
        "pattern": "/DDR5 SODIMM/B.~{DM0}"
      },
      {
        "netclass": "40Ohm-se_DQ",
        "pattern": "/DDR5 SODIMM/B.~{DM1}"
      },
      {
        "netclass": "40Ohm-se_DQ",
        "pattern": "/DDR5 SODIMM/B.~{DM2}"
      },
      {
        "netclass": "40Ohm-se_DQ",
        "pattern": "/DDR5 SODIMM/B.~{DM3}"
      },
      {
        "netclass": "50Ohm-se",
        "pattern": "/DDR5 SODIMM/A.CA0"
      },
      {
        "netclass": "50Ohm-se",
        "pattern": "/DDR5 SODIMM/A.CA1"
      },
      {
        "netclass": "50Ohm-se",
        "pattern": "/DDR5 SODIMM/A.CA10"
      },
      {
        "netclass": "50Ohm-se",
        "pattern": "/DDR5 SODIMM/A.CA11"
      },
      {
        "netclass": "50Ohm-se",
        "pattern": "/DDR5 SODIMM/A.CA12"
      },
      {
        "netclass": "50Ohm-se",
        "pattern": "/DDR5 SODIMM/A.CA2"
      },
      {
        "netclass": "50Ohm-se",
        "pattern": "/DDR5 SODIMM/A.CA3"
      },
      {
        "netclass": "50Ohm-se",
        "pattern": "/DDR5 SODIMM/A.CA4"
      },
      {
        "netclass": "50Ohm-se",
        "pattern": "/DDR5 SODIMM/A.CA5"
      },
      {
        "netclass": "50Ohm-se",
        "pattern": "/DDR5 SODIMM/A.CA6"
      },
      {
        "netclass": "50Ohm-se",
        "pattern": "/DDR5 SODIMM/A.CA7"
      },
      {
        "netclass": "50Ohm-se",
        "pattern": "/DDR5 SODIMM/A.CA8"
      },
      {
        "netclass": "50Ohm-se",
        "pattern": "/DDR5 SODIMM/A.CA9"
      },
      {
        "netclass": "50Ohm-se",
        "pattern": "/DDR5 SODIMM/A.CB0"
      },
      {
        "netclass": "50Ohm-se",
        "pattern": "/DDR5 SODIMM/A.CB1"
      },
      {
        "netclass": "50Ohm-se",
        "pattern": "/DDR5 SODIMM/A.CB2"
      },
      {
        "netclass": "50Ohm-se",
        "pattern": "/DDR5 SODIMM/A.CB3"
      },
      {
        "netclass": "50Ohm-se",
        "pattern": "/DDR5 SODIMM/A.~{CS0}"
      },
      {
        "netclass": "50Ohm-se",
        "pattern": "/DDR5 SODIMM/A.~{CS1}"
      },
      {
        "netclass": "50Ohm-se",
        "pattern": "/DDR5 SODIMM/B.CA0"
      },
      {
        "netclass": "50Ohm-se",
        "pattern": "/DDR5 SODIMM/B.CA1"
      },
      {
        "netclass": "50Ohm-se",
        "pattern": "/DDR5 SODIMM/B.CA10"
      },
      {
        "netclass": "50Ohm-se",
        "pattern": "/DDR5 SODIMM/B.CA11"
      },
      {
        "netclass": "50Ohm-se",
        "pattern": "/DDR5 SODIMM/B.CA12"
      },
      {
        "netclass": "50Ohm-se",
        "pattern": "/DDR5 SODIMM/B.CA2"
      },
      {
        "netclass": "50Ohm-se",
        "pattern": "/DDR5 SODIMM/B.CA3"
      },
      {
        "netclass": "50Ohm-se",
        "pattern": "/DDR5 SODIMM/B.CA4"
      },
      {
        "netclass": "50Ohm-se",
        "pattern": "/DDR5 SODIMM/B.CA5"
      },
      {
        "netclass": "50Ohm-se",
        "pattern": "/DDR5 SODIMM/B.CA6"
      },
      {
        "netclass": "50Ohm-se",
        "pattern": "/DDR5 SODIMM/B.CA7"
      },
      {
        "netclass": "50Ohm-se",
        "pattern": "/DDR5 SODIMM/B.CA8"
      },
      {
        "netclass": "50Ohm-se",
        "pattern": "/DDR5 SODIMM/B.CA9"
      },
      {
        "netclass": "50Ohm-se",
        "pattern": "/DDR5 SODIMM/B.CB0"
      },
      {
        "netclass": "50Ohm-se",
        "pattern": "/DDR5 SODIMM/B.CB1"
      },
      {
        "netclass": "50Ohm-se",
        "pattern": "/DDR5 SODIMM/B.CB2"
      },
      {
        "netclass": "50Ohm-se",
        "pattern": "/DDR5 SODIMM/B.CB3"
      },
      {
        "netclass": "50Ohm-se",
        "pattern": "/DDR5 SODIMM/B.~{CS0}"
      },
      {
        "netclass": "50Ohm-se",
        "pattern": "/DDR5 SODIMM/B.~{CS1}"
      },
      {
        "netclass": "50Ohm-se",
        "pattern": "/Ethernet/ETH.MDC"
      },
      {
        "netclass": "50Ohm-se",
        "pattern": "/Ethernet/ETH.MDIO"
      },
      {
        "netclass": "50Ohm-se",
        "pattern": "/Ethernet/ETH.REF_CLK"
      },
      {
        "netclass": "50Ohm-se",
        "pattern": "/Ethernet/ETH.RXC"
      },
      {
        "netclass": "50Ohm-se",
        "pattern": "/Ethernet/ETH.RXD0"
      },
      {
        "netclass": "50Ohm-se",
        "pattern": "/Ethernet/ETH.RXD1"
      },
      {
        "netclass": "50Ohm-se",
        "pattern": "/Ethernet/ETH.RXD2"
      },
      {
        "netclass": "50Ohm-se",
        "pattern": "/Ethernet/ETH.RXD3"
      },
      {
        "netclass": "50Ohm-se",
        "pattern": "/Ethernet/ETH.RX_CTL"
      },
      {
        "netclass": "50Ohm-se",
        "pattern": "/Ethernet/ETH.TXC"
      },
      {
        "netclass": "50Ohm-se",
        "pattern": "/Ethernet/ETH.TXD0"
      },
      {
        "netclass": "50Ohm-se",
        "pattern": "/Ethernet/ETH.TXD1"
      },
      {
        "netclass": "50Ohm-se",
        "pattern": "/Ethernet/ETH.TXD2"
      },
      {
        "netclass": "50Ohm-se",
        "pattern": "/Ethernet/ETH.TXD3"
      },
      {
        "netclass": "50Ohm-se",
        "pattern": "/Ethernet/ETH.TX_CTL"
      },
      {
        "netclass": "50Ohm-se",
        "pattern": "/Ethernet/ETH.~{INT}"
      },
      {
        "netclass": "50Ohm-se",
        "pattern": "/Ethernet/ETH.~{RESET}"
      },
      {
        "netclass": "50Ohm-se",
        "pattern": "/FPGA Config/FLASH.IO0"
      },
      {
        "netclass": "50Ohm-se",
        "pattern": "/FPGA Config/FLASH.IO1"
      },
      {
        "netclass": "50Ohm-se",
        "pattern": "/FPGA Config/FLASH.IO2"
      },
      {
        "netclass": "50Ohm-se",
        "pattern": "/FPGA Config/FLASH.IO3"
      },
      {
        "netclass": "50Ohm-se",
        "pattern": "/FPGA Config/FLASH.SCK"
      },
      {
        "netclass": "50Ohm-se",
        "pattern": "/FPGA Config/FLASH.~{CS}"
      },
      {
        "netclass": "50Ohm-se",
        "pattern": "/FPGA bank 12/HyperRAM.DQ0"
      },
      {
        "netclass": "50Ohm-se",
        "pattern": "/FPGA bank 12/HyperRAM.DQ1"
      },
      {
        "netclass": "50Ohm-se",
        "pattern": "/FPGA bank 12/HyperRAM.DQ2"
      },
      {
        "netclass": "50Ohm-se",
        "pattern": "/FPGA bank 12/HyperRAM.DQ3"
      },
      {
        "netclass": "50Ohm-se",
        "pattern": "/FPGA bank 12/HyperRAM.DQ4"
      },
      {
        "netclass": "50Ohm-se",
        "pattern": "/FPGA bank 12/HyperRAM.DQ5"
      },
      {
        "netclass": "50Ohm-se",
        "pattern": "/FPGA bank 12/HyperRAM.DQ6"
      },
      {
        "netclass": "50Ohm-se",
        "pattern": "/FPGA bank 12/HyperRAM.DQ7"
      },
      {
        "netclass": "50Ohm-se",
        "pattern": "/FPGA bank 12/HyperRAM.RWDS"
      },
      {
        "netclass": "50Ohm-se",
        "pattern": "/FPGA bank 12/HyperRAM.~{CS}"
      },
      {
        "netclass": "50Ohm-se",
        "pattern": "/FPGA bank 12/HyperRAM.~{RESET}"
      },
      {
        "netclass": "50Ohm-se",
        "pattern": "/FPGA bank 16/GCLK100"
      },
      {
        "netclass": "50Ohm-se",
        "pattern": "/FPGA bank 16/SD.CD"
      },
      {
        "netclass": "50Ohm-se",
        "pattern": "/FPGA bank 16/SD.CLK"
      },
      {
        "netclass": "50Ohm-se",
        "pattern": "/FPGA bank 16/SD.CMD"
      },
      {
        "netclass": "50Ohm-se",
        "pattern": "/FPGA bank 16/SD.DAT0"
      },
      {
        "netclass": "50Ohm-se",
        "pattern": "/FPGA bank 16/SD.DAT1"
      },
      {
        "netclass": "50Ohm-se",
        "pattern": "/FPGA bank 16/SD.DAT2"
      },
      {
        "netclass": "50Ohm-se",
        "pattern": "/FPGA bank 16/SD.DAT3"
      },
      {
        "netclass": "50Ohm-se",
        "pattern": "/HyperRAM + QSPI Flash/IO0"
      },
      {
        "netclass": "50Ohm-se",
        "pattern": "/HyperRAM + QSPI Flash/IO1"
      },
      {
        "netclass": "50Ohm-se",
        "pattern": "/HyperRAM + QSPI Flash/IO2"
      },
      {
        "netclass": "50Ohm-se",
        "pattern": "/HyperRAM + QSPI Flash/IO3"
      },
      {
        "netclass": "80Ohm-diff_DQS",
        "pattern": "/DDR5 SODIMM/A.DQS0_N"
      },
      {
        "netclass": "80Ohm-diff_DQS",
        "pattern": "/DDR5 SODIMM/A.DQS0_P"
      },
      {
        "netclass": "80Ohm-diff_DQS",
        "pattern": "/DDR5 SODIMM/A.DQS1_N"
      },
      {
        "netclass": "80Ohm-diff_DQS",
        "pattern": "/DDR5 SODIMM/A.DQS1_P"
      },
      {
        "netclass": "80Ohm-diff_DQS",
        "pattern": "/DDR5 SODIMM/A.DQS2_N"
      },
      {
        "netclass": "80Ohm-diff_DQS",
        "pattern": "/DDR5 SODIMM/A.DQS2_P"
      },
      {
        "netclass": "80Ohm-diff_DQS",
        "pattern": "/DDR5 SODIMM/A.DQS3_N"
      },
      {
        "netclass": "80Ohm-diff_DQS",
        "pattern": "/DDR5 SODIMM/A.DQS3_P"
      },
      {
        "netclass": "80Ohm-diff_DQS",
        "pattern": "/DDR5 SODIMM/A.DQS4_N"
      },
      {
        "netclass": "80Ohm-diff_DQS",
        "pattern": "/DDR5 SODIMM/A.DQS4_P"
      },
      {
        "netclass": "80Ohm-diff_DQS",
        "pattern": "/DDR5 SODIMM/B.DQS0_N"
      },
      {
        "netclass": "80Ohm-diff_DQS",
        "pattern": "/DDR5 SODIMM/B.DQS0_P"
      },
      {
        "netclass": "80Ohm-diff_DQS",
        "pattern": "/DDR5 SODIMM/B.DQS1_N"
      },
      {
        "netclass": "80Ohm-diff_DQS",
        "pattern": "/DDR5 SODIMM/B.DQS1_P"
      },
      {
        "netclass": "80Ohm-diff_DQS",
        "pattern": "/DDR5 SODIMM/B.DQS2_N"
      },
      {
        "netclass": "80Ohm-diff_DQS",
        "pattern": "/DDR5 SODIMM/B.DQS2_P"
      },
      {
        "netclass": "80Ohm-diff_DQS",
        "pattern": "/DDR5 SODIMM/B.DQS3_N"
      },
      {
        "netclass": "80Ohm-diff_DQS",
        "pattern": "/DDR5 SODIMM/B.DQS3_P"
      },
      {
        "netclass": "80Ohm-diff_DQS",
        "pattern": "/DDR5 SODIMM/B.DQS4_N"
      },
      {
        "netclass": "80Ohm-diff_DQS",
        "pattern": "/DDR5 SODIMM/B.DQS4_P"
      },
      {
        "netclass": "85Ohm-diff_PCIe",
        "pattern": "/FPGA MGT Interface/GTR_REFCLK0_N"
      },
      {
        "netclass": "85Ohm-diff_PCIe",
        "pattern": "/FPGA MGT Interface/GTR_REFCLK0_P"
      },
      {
        "netclass": "85Ohm-diff_PCIe",
        "pattern": "/FPGA MGT Interface/GTX_TX0_N"
      },
      {
        "netclass": "85Ohm-diff_PCIe",
        "pattern": "/FPGA MGT Interface/GTX_TX0_P"
      },
      {
        "netclass": "85Ohm-diff_PCIe",
        "pattern": "/FPGA MGT Interface/GTX_TX1_N"
      },
      {
        "netclass": "85Ohm-diff_PCIe",
        "pattern": "/FPGA MGT Interface/GTX_TX1_P"
      },
      {
        "netclass": "85Ohm-diff_PCIe",
        "pattern": "/FPGA MGT Interface/GTX_TX2_N"
      },
      {
        "netclass": "85Ohm-diff_PCIe",
        "pattern": "/FPGA MGT Interface/GTX_TX2_P"
      },
      {
        "netclass": "85Ohm-diff_PCIe",
        "pattern": "/FPGA MGT Interface/GTX_TX3_N"
      },
      {
        "netclass": "85Ohm-diff_PCIe",
        "pattern": "/FPGA MGT Interface/GTX_TX3_P"
      },
      {
        "netclass": "85Ohm-diff_PCIe",
        "pattern": "/FPGA MGT Interface/PCIE.CLK_N"
      },
      {
        "netclass": "85Ohm-diff_PCIe",
        "pattern": "/FPGA MGT Interface/PCIE.CLK_P"
      },
      {
        "netclass": "85Ohm-diff_PCIe",
        "pattern": "/FPGA MGT Interface/PCIE.RXD0_N"
      },
      {
        "netclass": "85Ohm-diff_PCIe",
        "pattern": "/FPGA MGT Interface/PCIE.RXD0_P"
      },
      {
        "netclass": "85Ohm-diff_PCIe",
        "pattern": "/FPGA MGT Interface/PCIE.RXD1_N"
      },
      {
        "netclass": "85Ohm-diff_PCIe",
        "pattern": "/FPGA MGT Interface/PCIE.RXD1_P"
      },
      {
        "netclass": "85Ohm-diff_PCIe",
        "pattern": "/FPGA MGT Interface/PCIE.RXD2_N"
      },
      {
        "netclass": "85Ohm-diff_PCIe",
        "pattern": "/FPGA MGT Interface/PCIE.RXD2_P"
      },
      {
        "netclass": "85Ohm-diff_PCIe",
        "pattern": "/FPGA MGT Interface/PCIE.RXD3_N"
      },
      {
        "netclass": "85Ohm-diff_PCIe",
        "pattern": "/FPGA MGT Interface/PCIE.RXD3_P"
      },
      {
        "netclass": "85Ohm-diff_PCIe",
        "pattern": "/FPGA MGT Interface/PCIE.TXD0_N"
      },
      {
        "netclass": "85Ohm-diff_PCIe",
        "pattern": "/FPGA MGT Interface/PCIE.TXD0_P"
      },
      {
        "netclass": "85Ohm-diff_PCIe",
        "pattern": "/FPGA MGT Interface/PCIE.TXD1_N"
      },
      {
        "netclass": "85Ohm-diff_PCIe",
        "pattern": "/FPGA MGT Interface/PCIE.TXD1_P"
      },
      {
        "netclass": "85Ohm-diff_PCIe",
        "pattern": "/FPGA MGT Interface/PCIE.TXD2_N"
      },
      {
        "netclass": "85Ohm-diff_PCIe",
        "pattern": "/FPGA MGT Interface/PCIE.TXD2_P"
      },
      {
        "netclass": "85Ohm-diff_PCIe",
        "pattern": "/FPGA MGT Interface/PCIE.TXD3_N"
      },
      {
        "netclass": "85Ohm-diff_PCIe",
        "pattern": "/FPGA MGT Interface/PCIE.TXD3_P"
      },
      {
        "netclass": "90Ohm-diff",
        "pattern": "/Debug FTDI/DBG_USB_N"
      },
      {
        "netclass": "90Ohm-diff",
        "pattern": "/Debug FTDI/DBG_USB_P"
      },
      {
        "netclass": "Supply",
        "pattern": "+1V0"
      },
      {
        "netclass": "Supply",
        "pattern": "+1V0_MGTAVCC"
      },
      {
        "netclass": "Supply",
        "pattern": "+1V1"
      },
      {
        "netclass": "Supply",
        "pattern": "+1V2"
      },
      {
        "netclass": "Supply",
        "pattern": "+1V2_MGTAVTT"
      },
      {
        "netclass": "Supply",
        "pattern": "+1V8"
      },
      {
        "netclass": "Supply",
        "pattern": "+3V3"
      },
      {
        "netclass": "Supply",
        "pattern": "+3V3_AON"
      },
      {
        "netclass": "Supply",
        "pattern": "+5V"
      },
      {
        "netclass": "Supply",
        "pattern": "/Debug FTDI/VBUS"
      },
      {
        "netclass": "Supply",
        "pattern": "/Ethernet/AVDDH"
      },
      {
        "netclass": "Supply",
        "pattern": "/Ethernet/AVDDL"
      },
      {
        "netclass": "Supply",
        "pattern": "/Ethernet/AVDDL_PLL"
      },
      {
        "netclass": "Supply",
        "pattern": "/Supply/1V0_BS"
      },
      {
        "netclass": "Supply",
        "pattern": "/Supply/1V0_FB"
      },
      {
        "netclass": "Supply",
        "pattern": "/Supply/1V0_REG"
      },
      {
        "netclass": "Supply",
        "pattern": "/Supply/1V0_SS"
      },
      {
        "netclass": "Supply",
        "pattern": "/Supply/1V0_SW"
      },
      {
        "netclass": "Supply",
        "pattern": "/Supply/1V0_VCC"
      },
      {
        "netclass": "Supply",
        "pattern": "/Supply/1V1_SEN_+"
      },
      {
        "netclass": "Supply",
        "pattern": "/Supply/1V1_SEN_-"
      },
      {
        "netclass": "Supply",
        "pattern": "/Supply/1V1_local"
      },
      {
        "netclass": "Supply",
        "pattern": "/Supply/1V2_SEN_+"
      },
      {
        "netclass": "Supply",
        "pattern": "/Supply/1V2_SEN_-"
      },
      {
        "netclass": "Supply",
        "pattern": "/Supply/1V2_local"
      },
      {
        "netclass": "Supply",
        "pattern": "/Supply/1V7"
      },
      {
        "netclass": "Supply",
        "pattern": "/Supply/1V7_SEN_+"
      },
      {
        "netclass": "Supply",
        "pattern": "/Supply/1V7_SEN_-"
      },
      {
        "netclass": "Supply",
        "pattern": "/Supply/1V7_local"
      },
      {
        "netclass": "Supply",
        "pattern": "/Supply/1V8_SEN_+"
      },
      {
        "netclass": "Supply",
        "pattern": "/Supply/1V8_SEN_-"
      },
      {
        "netclass": "Supply",
        "pattern": "/Supply/1V8_local"
      },
      {
        "netclass": "Supply",
        "pattern": "/Supply/3V3_SEN_+"
      },
      {
        "netclass": "Supply",
        "pattern": "/Supply/3V3_SEN_-"
      },
      {
        "netclass": "Supply",
        "pattern": "/Supply/3V3_local"
      },
      {
        "netclass": "Supply",
        "pattern": "/Supply/5V_SEN_+"
      },
      {
        "netclass": "Supply",
        "pattern": "/Supply/5V_SEN_-"
      },
      {
        "netclass": "Supply",
        "pattern": "/Supply/5V_local"
      },
      {
        "netclass": "Supply",
        "pattern": "/Supply/spare"
      },
      {
        "netclass": "Supply",
        "pattern": "/Supply/spare_local"
      },
      {
        "netclass": "Supply",
        "pattern": "DAC_VREF"
      },
      {
        "netclass": "Supply",
        "pattern": "GND"
      }
    ]
  },
  "pcbnew": {
    "last_paths": {
      "gencad": "",
      "idf": "",
      "netlist": "",
      "plot": "",
      "pos_files": "",
      "specctra_dsn": "",
      "step": "",
      "svg": "",
      "vrml": "data-center-rdimm-ddr4-tester.wrl"
    },
    "page_layout_descr_file": ""
  },
  "schematic": {
    "annotate_start_num": 0,
    "bom_export_filename": "${PROJECTNAME}.csv",
    "bom_fmt_presets": [],
    "bom_fmt_settings": {
      "field_delimiter": ",",
      "keep_line_breaks": false,
      "keep_tabs": false,
      "name": "CSV",
      "ref_delimiter": ",",
      "ref_range_delimiter": "",
      "string_delimiter": "\""
    },
    "bom_presets": [],
    "bom_settings": {
      "exclude_dnp": false,
      "fields_ordered": [
        {
          "group_by": false,
          "label": "Reference",
          "name": "Reference",
          "show": true
        },
        {
          "group_by": false,
          "label": "Qty",
          "name": "${QUANTITY}",
          "show": true
        },
        {
          "group_by": true,
          "label": "Value",
          "name": "Value",
          "show": true
        },
        {
          "group_by": true,
          "label": "DNP",
          "name": "${DNP}",
          "show": true
        },
        {
          "group_by": true,
          "label": "Exclude from BOM",
          "name": "${EXCLUDE_FROM_BOM}",
          "show": true
        },
        {
          "group_by": true,
          "label": "Exclude from Board",
          "name": "${EXCLUDE_FROM_BOARD}",
          "show": true
        },
        {
          "group_by": true,
          "label": "Footprint",
          "name": "Footprint",
          "show": true
        },
        {
          "group_by": false,
          "label": "Datasheet",
          "name": "Datasheet",
          "show": true
        }
      ],
      "filter_string": "",
      "group_symbols": true,
      "include_excluded_from_bom": true,
      "name": "Default Editing",
      "sort_asc": true,
      "sort_field": "Reference"
    },
    "connection_grid_size": 50.0,
    "drawing": {
      "dashed_lines_dash_length_ratio": 12.0,
      "dashed_lines_gap_length_ratio": 3.0,
      "default_line_thickness": 6.0,
      "default_text_size": 50.0,
      "field_names": [],
      "intersheets_ref_own_page": false,
      "intersheets_ref_prefix": "Pg. ",
      "intersheets_ref_short": false,
      "intersheets_ref_show": true,
      "intersheets_ref_suffix": "",
      "junction_size_choice": 3,
      "label_size_ratio": 0.25,
      "operating_point_overlay_i_precision": 3,
      "operating_point_overlay_i_range": "~A",
      "operating_point_overlay_v_precision": 3,
      "operating_point_overlay_v_range": "~V",
      "overbar_offset_ratio": 1.23,
      "pin_symbol_size": 0.0,
      "text_offset_ratio": 0.08
    },
    "legacy_lib_dir": "",
    "legacy_lib_list": [],
    "meta": {
      "version": 1
    },
    "net_format_name": "Pcbnew",
    "ngspice": {
      "fix_include_paths": true,
      "fix_passive_vals": false,
      "meta": {
        "version": 0
      },
      "model_mode": 0,
      "workbook_filename": ""
    },
    "page_layout_descr_file": "",
    "plot_directory": "./doc",
    "space_save_all_events": true,
    "spice_adjust_passive_values": false,
    "spice_current_sheet_as_root": false,
    "spice_external_command": "spice \"%I\"",
    "spice_model_current_sheet_as_root": true,
    "spice_save_all_currents": false,
    "spice_save_all_dissipations": false,
    "spice_save_all_voltages": false,
    "subpart_first_id": 65,
    "subpart_id_separator": 0
  },
  "sheets": [
    [
      "",
      "Root"
    ],
    [
      "",
      "HyperRAM + QSPI Flash"
    ],
    [
      "",
      "FPGA Config"
    ],
    [
      "",
      "DDR5 SODIMM"
    ],
    [
      "",
      "FPGA power"
    ],
    [
      "",
      "Debug FTDI"
    ],
    [
      "",
      "Ethernet"
    ],
    [
      "",
      "FPGA banks HP"
    ],
    [
      "",
      "Supply"
    ],
    [
      "",
      "FPGA MGT Interface"
    ],
    [
      "",
      "PCIe connector"
    ],
    [
      "",
      "FPGA bank 12"
    ],
    [
      "",
      "FPGA banks unused"
    ],
    [
      "",
      "FPGA bank 14"
    ],
    [
      "",
      "FPGA bank 16"
    ],
    [
      "",
      "I^{2}C"
    ],
    [
      "",
      "HDMI + SD Card"
    ]
  ],
  "text_variables": {}
}
